# T6G (Grand Teton) — schematic netlist excerpt (pin names and nets, part order shuffled) for the footprints in the layout excerpt that follows; sources: Cadence DE-HDL packaged netlist, KiCad conversion of 04192023_DAF0TMB3IC0_F0TG_MB_C_brd_V02_OCP.brd

J68  SCONN288_DDR506112002KQ  IO  pkg DDR288S_1-1VXC  page 95
  VIN_BULK0  = P12V_MEM_CPU0
  RFU0  = NC
  VIN_MGMT  = P3V3_AUX
  HSCL  = I3C_SPD_DDRJ_CPU0_SCL
  HSDA  = I3C_SPD_DDRJ_CPU0_SDA
  VSS0  = GND
  DQ0_A  = M_J_CPU0_SA_DQ<0>
  VSS1  = GND
  DQ1_A  = M_J_CPU0_SA_DQ<1>
  VSS2  = GND
  DQS0_A_T  = M_J_CPU0_SA_DQS_DP<0>
  DQS0_A_C  = M_J_CPU0_SA_DQS_DN<0>
  VSS3  = GND
  DQ4_A  = M_J_CPU0_SA_DQ<4>
  VSS4  = GND
  DQ5_A  = M_J_CPU0_SA_DQ<5>
  VSS5  = GND
  DQ8_A  = M_J_CPU0_SA_DQ<8>
  VSS6  = GND
  DQ9_A  = M_J_CPU0_SA_DQ<9>
  VSS7  = GND
  DQS1_A_T  = M_J_CPU0_SA_DQS_DP<1>
  DQS1_A_C  = M_J_CPU0_SA_DQS_DN<1>
  VSS8  = GND
  DQ12_A  = M_J_CPU0_SA_DQ<12>
  VSS9  = GND
  DQ13_A  = M_J_CPU0_SA_DQ<13>
  VSS10  = GND
  DQ16_A  = M_J_CPU0_SA_DQ<16>
  VSS11  = GND
  DQ17_A  = M_J_CPU0_SA_DQ<17>
  VSS12  = GND
  DQS2_A_T  = M_J_CPU0_SA_DQS_DP<2>
  DQS2_A_C  = M_J_CPU0_SA_DQS_DN<2>
  VSS13  = GND
  DQ20_A  = M_J_CPU0_SA_DQ<20>
  VSS14  = GND
  DQ21_A  = M_J_CPU0_SA_DQ<21>
  VSS15  = GND
  DQ24_A  = M_J_CPU0_SA_DQ<24>
  VSS16  = GND
  DQ25_A  = M_J_CPU0_SA_DQ<25>
  VSS17  = GND
  DQS3_A_T  = M_J_CPU0_SA_DQS_DP<3>
  DQS3_A_C  = M_J_CPU0_SA_DQS_DN<3>
  VSS18  = GND
  DQ28_A  = M_J_CPU0_SA_DQ<28>
  VSS19  = GND
  DQ29_A  = M_J_CPU0_SA_DQ<29>
  VSS20  = GND
  CB0_A  = M_J_CPU0_SA_CB<0>
  VSS21  = GND
  CB1_A  = M_J_CPU0_SA_CB<1>
  VSS22  = GND
  DQS4_A_T  = M_J_CPU0_SA_DQS_DP<4>
  DQS4_A_C  = M_J_CPU0_SA_DQS_DN<4>
  VSS23  = GND
  CB4_A  = M_J_CPU0_SA_CB<4>
  VSS24  = GND
  CB5_A  = M_J_CPU0_SA_CB<5>
  VSS25  = GND
  ALERT_N  = M_J_CPU0_ALERT_N
  VSS26  = GND
  CS0_A_N  = M_J_CPU0_SA_CS_N<0>
  VSS27  = GND
  CA0_A  = M_J_CPU0_SA_CA<0>
  VSS28  = GND
  CA2_A  = M_J_CPU0_SA_CA<2>
  VSS29  = GND
  CA4_A  = M_J_CPU0_SA_CA<4>
  VSS30  = GND
  CA6_A  = M_J_CPU0_SA_CA<6>
  VSS31  = GND
  PAR_A  = M_J_CPU0_SA_PAR
  VSS32  = GND
  CA0_B  = M_J_CPU0_SB_CA<0>
  VSS33  = GND
  CA2_B  = M_J_CPU0_SB_CA<2>
  VSS34  = GND
  CA4_B  = M_J_CPU0_SB_CA<4>
  VSS35  = GND
  CA6_B  = M_J_CPU0_SB_CA<6>
  VSS36  = GND
  CS0_B_N  = M_J_CPU0_SB_CS_N<0>
  VSS37  = GND
  \lbd||rsp_a_n\  = M_J_CPU0_SA_RSP<0>
  \lbs||rsp_b_n\  = M_J_CPU0_SB_RSP<0>
  VSS38  = GND
  CB4_B  = M_J_CPU0_SB_CB<4>
  VSS39  = GND
  CB5_B  = M_J_CPU0_SB_CB<5>
  VSS40  = GND
  \dqs9_b_t||tdqs9_b_t||dbi4_b_n\  = M_J_CPU0_SB_DQS_DP<9>
  \dqs9_b_c||tdqs9_b_c\  = M_J_CPU0_SB_DQS_DN<9>
  VSS41  = GND
  CB0_B  = M_J_CPU0_SB_CB<0>
  VSS42  = GND
  CB1_B  = M_J_CPU0_SB_CB<1>
  VSS43  = GND
  DQ0_B  = M_J_CPU0_SB_DQ<0>
  VSS44  = GND
  DQ1_B  = M_J_CPU0_SB_DQ<1>
  VSS45  = GND
  DQS0_B_T  = M_J_CPU0_SB_DQS_DP<0>
  DQS0_B_C  = M_J_CPU0_SB_DQS_DN<0>
  VSS46  = GND
  DQ4_B  = M_J_CPU0_SB_DQ<4>
  VSS47  = GND
  DQ5_B  = M_J_CPU0_SB_DQ<5>
  VSS48  = GND
  DQ8_B  = M_J_CPU0_SB_DQ<8>
  VSS49  = GND
  DQ9_B  = M_J_CPU0_SB_DQ<9>
  VSS50  = GND
  DQS1_B_T  = M_J_CPU0_SB_DQS_DP<1>
  DQS1_B_C  = M_J_CPU0_SB_DQS_DN<1>
  VSS51  = GND
  DQ12_B  = M_J_CPU0_SB_DQ<12>
  VSS52  = GND
  DQ13_B  = M_J_CPU0_SB_DQ<13>
  VSS53  = GND
  DQ16_B  = M_J_CPU0_SB_DQ<16>
  VSS54  = GND
  DQ17_B  = M_J_CPU0_SB_DQ<17>
  VSS55  = GND
  DQS2_B_T  = M_J_CPU0_SB_DQS_DP<2>
  DQS2_B_C  = M_J_CPU0_SB_DQS_DN<2>
  VSS56  = GND
  DQ20_B  = M_J_CPU0_SB_DQ<20>
  VSS57  = GND
  DQ21_B  = M_J_CPU0_SB_DQ<21>
  VSS58  = GND
  DQ24_B  = M_J_CPU0_SB_DQ<24>
  VSS59  = GND
  DQ25_B  = M_J_CPU0_SB_DQ<25>
  VSS60  = GND
  DQS3_B_T  = M_J_CPU0_SB_DQS_DP<3>
  DQS3_B_C  = M_J_CPU0_SB_DQS_DN<3>
  VSS61  = GND
  DQ28_B  = M_J_CPU0_SB_DQ<28>
  VSS62  = GND
  DQ29_B  = M_J_CPU0_SB_DQ<29>
  VSS63  = GND
  RFU1  = NC
  VIN_BULK1  = P12V_MEM_CPU0
  VIN_BULK2  = P12V_MEM_CPU0
  \pwr_good||fail_n\  = PWRGD_CHJ_CPU0_DIMM
  HAS  = PD_CHJ_CPU0_DIMM_SAA
  RFU2  = NC
  RFU3  = NC
  VSS64  = GND
  DQ2_A  = M_J_CPU0_SA_DQ<2>
  VSS65  = GND
  DQ3_A  = M_J_CPU0_SA_DQ<3>
  VSS66  = GND
  \dqs5_a_c||tdqs5_a_c||dqs5_a_t||tdqs5_a_t\  = M_J_CPU0_SA_DQS_DN<5>
  \dqs5_a_t||tdqs5_a_t\  = M_J_CPU0_SA_DQS_DP<5>
  VSS67  = GND
  DQ6_A  = M_J_CPU0_SA_DQ<6>
  VSS68  = GND
  DQ7_A  = M_J_CPU0_SA_DQ<7>
  VSS69  = GND
  DQ10_A  = M_J_CPU0_SA_DQ<10>
  VSS70  = GND
  DQ11_A  = M_J_CPU0_SA_DQ<11>
  VSS71  = GND
  \dqs6_a_c||tdqs6_a_c||dqs6_a_t||tdqs6_a_t\  = M_J_CPU0_SA_DQS_DN<6>
  \dqs6_a_t||tdqs6_a_t\  = M_J_CPU0_SA_DQS_DP<6>
  VSS72  = GND
  DQ14_A  = M_J_CPU0_SA_DQ<14>
  VSS73  = GND
  DQ15_A  = M_J_CPU0_SA_DQ<15>
  VSS74  = GND
  DQ18_A  = M_J_CPU0_SA_DQ<18>
  VSS75  = GND
  DQ19_A  = M_J_CPU0_SA_DQ<19>
  VSS76  = GND
  \dqs7_a_c||tdqs7_a_c\  = M_J_CPU0_SA_DQS_DN<7>
  \dqs7_a_t||tdqs7_a_t\  = M_J_CPU0_SA_DQS_DP<7>
  VSS77  = GND
  DQ22_A  = M_J_CPU0_SA_DQ<22>
  VSS78  = GND
  DQ23_A  = M_J_CPU0_SA_DQ<23>
  VSS79  = GND
  DQ26_A  = M_J_CPU0_SA_DQ<26>
  VSS80  = GND
  DQ27_A  = M_J_CPU0_SA_DQ<27>
  VSS81  = GND
  \dqs8_a_c||tdqs8_a_c\  = M_J_CPU0_SA_DQS_DN<8>
  \dqs8_a_t||tdqs8_a_t\  = M_J_CPU0_SA_DQS_DP<8>
  VSS82  = GND
  DQ30_A  = M_J_CPU0_SA_DQ<30>
  VSS83  = GND
  DQ31_A  = M_J_CPU0_SA_DQ<31>
  VSS84  = GND
  CB2_A  = M_J_CPU0_SA_CB<2>
  VSS85  = GND
  CB3_A  = M_J_CPU0_SA_CB<3>
  VSS86  = GND
  \dqs9_a_c||tdqs9_a_c\  = M_J_CPU0_SA_DQS_DN<9>
  \dqs9_a_t||tdqs9_a_t\  = M_J_CPU0_SA_DQS_DP<9>
  VSS87  = GND
  CB6_A  = M_J_CPU0_SA_CB<6>
  VSS88  = GND
  CB7_A  = M_J_CPU0_SA_CB<7>
  VSS89  = GND
  RESET_N  = M_J_CPU0_RESET_N
  VSS90  = GND
  CS1_A_N  = M_J_CPU0_SA_CS_N<1>
  VSS91  = GND
  CA1_A  = M_J_CPU0_SA_CA<1>
  VSS92  = GND
  CA3_A  = M_J_CPU0_SA_CA<3>
  VSS93  = GND
  CA5_A  = M_J_CPU0_SA_CA<5>
  VSS94  = GND
  CK_T  = M_J_CPU0_CLK_DP<0>
  CK_C  = M_J_CPU0_CLK_DN<0>
  VSS95  = GND
  RFU4  = NC
  CA1_B  = M_J_CPU0_SB_CA<1>
  VSS96  = GND
  CA3_B  = M_J_CPU0_SB_CA<3>
  VSS97  = GND
  CA5_B  = M_J_CPU0_SB_CA<5>
  VSS98  = GND
  PAR_B  = M_J_CPU0_SB_PAR
  VSS99  = GND
  CS1_B_N  = M_J_CPU0_SB_CS_N<1>
  VSS100  = GND
  RFU5  = NC
  RFU6  = NC
  VSS101  = GND
  CB6_B  = M_J_CPU0_SB_CB<6>
  VSS102  = GND
  CB7_B  = M_J_CPU0_SB_CB<7>
  VSS103  = GND
  DQS4_B_C  = M_J_CPU0_SB_DQS_DN<4>
  DQS4_B_T  = M_J_CPU0_SB_DQS_DP<4>
  VSS104  = GND
  CB2_B  = M_J_CPU0_SB_CB<2>
  VSS105  = GND
  CB3_B  = M_J_CPU0_SB_CB<3>
  VSS106  = GND
  DQ2_B  = M_J_CPU0_SB_DQ<2>
  VSS107  = GND
  DQ3_B  = M_J_CPU0_SB_DQ<3>
  VSS108  = GND
  \dqs5_b_c||tdqs5_b_c\  = M_J_CPU0_SB_DQS_DN<5>
  \dqs5_b_t||tdqs5_b_t\  = M_J_CPU0_SB_DQS_DP<5>
  VSS109  = GND
  DQ6_B  = M_J_CPU0_SB_DQ<6>
  VSS110  = GND
  DQ7_B  = M_J_CPU0_SB_DQ<7>
  VSS111  = GND
  DQ10_B  = M_J_CPU0_SB_DQ<10>
  VSS112  = GND
  DQ11_B  = M_J_CPU0_SB_DQ<11>
  VSS113  = GND
  \dqs6_b_c||tdqs6_b_c\  = M_J_CPU0_SB_DQS_DN<6>
  \dqs6_b_t||tdqs6_b_t\  = M_J_CPU0_SB_DQS_DP<6>
  VSS114  = GND
  DQ14_B  = M_J_CPU0_SB_DQ<14>
  VSS115  = GND
  DQ15_B  = M_J_CPU0_SB_DQ<15>
  VSS116  = GND
  DQ18_B  = M_J_CPU0_SB_DQ<18>
  VSS117  = GND
  DQ19_B  = M_J_CPU0_SB_DQ<19>
  VSS118  = GND
  \dqs7_b_c||tdqs7_b_c\  = M_J_CPU0_SB_DQS_DN<7>
  \dqs7_b_t||tdqs7_b_t\  = M_J_CPU0_SB_DQS_DP<7>
  VSS119  = GND
  DQ22_B  = M_J_CPU0_SB_DQ<22>
  VSS120  = GND
  DQ23_B  = M_J_CPU0_SB_DQ<23>
  VSS121  = GND
  DQ26_B  = M_J_CPU0_SB_DQ<26>
  VSS122  = GND
  DQ27_B  = M_J_CPU0_SB_DQ<27>
  VSS123  = GND
  \dqs8_b_c||tdqs8_b_c\  = M_J_CPU0_SB_DQS_DN<8>
  \dqs8_b_t||tdqs8_b_t\  = M_J_CPU0_SB_DQS_DP<8>
  VSS124  = GND
  DQ30_B  = M_J_CPU0_SB_DQ<30>
  VSS125  = GND
  DQ31_B  = M_J_CPU0_SB_DQ<31>
  VSS126  = GND
  G1  = GND
  G2  = GND
  G3  = GND

(kicad_pcb
	(version 20260206)
	(generator "pcbnew")
	(generator_version "10.0")
	(general
		(thickness 1.6)
		(legacy_teardrops no)
	)
	(paper "A4")
	(title_block
		(title "04192023_DAF0TMB3IC0_F0TG_MB_C_brd_V02_OCP.brd")
		(comment 1 "Grand Teton / footprint 802 of 8354 (J68), pads 138-183 of 291")
	)
	(layers
		(0 "F.Cu" signal "TOP")
		(4 "In1.Cu" signal "GND")
		(6 "In2.Cu" signal "IN1")
		(8 "In3.Cu" signal "GND1")
		(10 "In4.Cu" signal "IN2")
		(12 "In5.Cu" signal "GND2")
		(14 "In6.Cu" signal "IN3")
		(16 "In7.Cu" signal "GND3")
		(18 "In8.Cu" signal "VCC")
		(20 "In9.Cu" signal "VCC1")
		(22 "In10.Cu" signal "GND4")
		(24 "In11.Cu" signal "IN4")
		(26 "In12.Cu" signal "GND5")
		(28 "In13.Cu" signal "IN5")
		(30 "In14.Cu" signal "GND6")
		(32 "In15.Cu" signal "IN6")
		(34 "In16.Cu" signal "GND7")
		(2 "B.Cu" signal "BOTTOM")
		(9 "F.Adhes" user "F.Adhesive")
		(11 "B.Adhes" user "B.Adhesive")
		(13 "F.Paste" user "Package Geometry/Pastemask Top")
		(15 "B.Paste" user "Package Geometry/Pastemask Bottom")
		(5 "F.SilkS" user "Ref Des/Silkscreen Top")
		(7 "B.SilkS" user "Ref Des/Silkscreen Bottom")
		(1 "F.Mask" user "Board Geometry/Soldermask Top")
		(3 "B.Mask" user "Board Geometry/Soldermask Bottom")
		(17 "Dwgs.User" user "User.Drawings")
		(19 "Cmts.User" user "User.Comments")
		(21 "Eco1.User" user "User.Eco1")
		(23 "Eco2.User" user "User.Eco2")
		(25 "Edge.Cuts" user "Board Geometry/Outline")
		(27 "Margin" user)
		(31 "F.CrtYd" user "Package Geometry/Place Bound Top")
		(29 "B.CrtYd" user "Package Geometry/Place Bound Bottom")
		(35 "F.Fab" user "Ref Des/Assembly Top")
		(33 "B.Fab" user "Ref Des/Assembly Bottom")
	)
	(footprint ""
		(layer "F.Cu")
		(at 437.05018 -255.560068 180)
		(property "Reference" "J68"
			(at 1.32334 -81.844388 0)
			(unlocked yes)
			(layer "F.SilkS")
			(effects
				(font
					(size 0.7874 0.5842)
					(thickness 0.1524)
				)
			)
		)
		(property "Value" ""
			(at 0 0 180)
			(layer "F.Fab")
			(effects
				(font
					(size 1.27 1.27)
				)
			)
		)
		(duplicate_pad_numbers_are_jumpers no)
		(pad "138" smd rect
			(at -2.050034 58.224928 90)
			(size 0.519938 1.4986)
			(layers "F.Cu" "F.Mask" "F.Paste")
			(net "M_J_CPU0_SB_DQS_DN<3>")
		)
		(pad "139" smd rect
			(at -2.050034 59.075066 90)
			(size 0.519938 1.4986)
			(layers "F.Cu" "F.Mask" "F.Paste")
			(net "GND")
		)
		(pad "140" smd rect
			(at -2.050034 59.92495 90)
			(size 0.519938 1.4986)
			(layers "F.Cu" "F.Mask" "F.Paste")
			(net "M_J_CPU0_SB_DQ<28>")
		)
		(pad "141" smd rect
			(at -2.050034 60.775088 90)
			(size 0.519938 1.4986)
			(layers "F.Cu" "F.Mask" "F.Paste")
			(net "GND")
		)
		(pad "142" smd rect
			(at -2.050034 61.624972 90)
			(size 0.519938 1.4986)
			(layers "F.Cu" "F.Mask" "F.Paste")
			(net "M_J_CPU0_SB_DQ<29>")
		)
		(pad "143" smd rect
			(at -2.050034 62.47511 90)
			(size 0.519938 1.4986)
			(layers "F.Cu" "F.Mask" "F.Paste")
			(net "GND")
		)
		(pad "144" smd rect
			(at -2.050034 63.324994 90)
			(size 0.519938 1.4986)
			(layers "F.Cu" "F.Mask" "F.Paste")
			(net "Net_2376")
		)
		(pad "145" smd rect
			(at 2.050034 -63.324994 90)
			(size 0.519938 1.4986)
			(layers "F.Cu" "F.Mask" "F.Paste")
			(net "P12V_MEM_CPU0")
		)
		(pad "146" smd rect
			(at 2.050034 -62.47511 90)
			(size 0.519938 1.4986)
			(layers "F.Cu" "F.Mask" "F.Paste")
			(net "P12V_MEM_CPU0")
		)
		(pad "147" smd rect
			(at 2.050034 -61.624972 90)
			(size 0.519938 1.4986)
			(layers "F.Cu" "F.Mask" "F.Paste")
			(net "PWRGD_CHJ_CPU0_DIMM")
		)
		(pad "148" smd rect
			(at 2.050034 -60.775088 90)
			(size 0.519938 1.4986)
			(layers "F.Cu" "F.Mask" "F.Paste")
			(net "PD_CHJ_CPU0_DIMM_SAA")
		)
		(pad "149" smd rect
			(at 2.050034 -59.92495 90)
			(size 0.519938 1.4986)
			(layers "F.Cu" "F.Mask" "F.Paste")
			(net "Net_2377")
		)
		(pad "150" smd rect
			(at 2.050034 -59.075066 90)
			(size 0.519938 1.4986)
			(layers "F.Cu" "F.Mask" "F.Paste")
			(net "Net_2378")
		)
		(pad "151" smd rect
			(at 2.050034 -58.224928 90)
			(size 0.519938 1.4986)
			(layers "F.Cu" "F.Mask" "F.Paste")
			(net "GND")
		)
		(pad "152" smd rect
			(at 2.050034 -57.375044 90)
			(size 0.519938 1.4986)
			(layers "F.Cu" "F.Mask" "F.Paste")
			(net "M_J_CPU0_SA_DQ<2>")
		)
		(pad "153" smd rect
			(at 2.050034 -56.524906 90)
			(size 0.519938 1.4986)
			(layers "F.Cu" "F.Mask" "F.Paste")
			(net "GND")
		)
		(pad "154" smd rect
			(at 2.050034 -55.675022 90)
			(size 0.519938 1.4986)
			(layers "F.Cu" "F.Mask" "F.Paste")
			(net "M_J_CPU0_SA_DQ<3>")
		)
		(pad "155" smd rect
			(at 2.050034 -54.824884 90)
			(size 0.519938 1.4986)
			(layers "F.Cu" "F.Mask" "F.Paste")
			(net "GND")
		)
		(pad "156" smd rect
			(at 2.050034 -53.975 90)
			(size 0.519938 1.4986)
			(layers "F.Cu" "F.Mask" "F.Paste")
			(net "M_J_CPU0_SA_DQS_DN<5>")
		)
		(pad "157" smd rect
			(at 2.050034 -53.125116 90)
			(size 0.519938 1.4986)
			(layers "F.Cu" "F.Mask" "F.Paste")
			(net "M_J_CPU0_SA_DQS_DP<5>")
		)
		(pad "158" smd rect
			(at 2.050034 -52.274978 90)
			(size 0.519938 1.4986)
			(layers "F.Cu" "F.Mask" "F.Paste")
			(net "GND")
		)
		(pad "159" smd rect
			(at 2.050034 -51.425094 90)
			(size 0.519938 1.4986)
			(layers "F.Cu" "F.Mask" "F.Paste")
			(net "M_J_CPU0_SA_DQ<6>")
		)
		(pad "160" smd rect
			(at 2.050034 -50.574956 90)
			(size 0.519938 1.4986)
			(layers "F.Cu" "F.Mask" "F.Paste")
			(net "GND")
		)
		(pad "161" smd rect
			(at 2.050034 -49.725072 90)
			(size 0.519938 1.4986)
			(layers "F.Cu" "F.Mask" "F.Paste")
			(net "M_J_CPU0_SA_DQ<7>")
		)
		(pad "162" smd rect
			(at 2.050034 -48.874934 90)
			(size 0.519938 1.4986)
			(layers "F.Cu" "F.Mask" "F.Paste")
			(net "GND")
		)
		(pad "163" smd rect
			(at 2.050034 -48.02505 90)
			(size 0.519938 1.4986)
			(layers "F.Cu" "F.Mask" "F.Paste")
			(net "M_J_CPU0_SA_DQ<10>")
		)
		(pad "164" smd rect
			(at 2.050034 -47.174912 90)
			(size 0.519938 1.4986)
			(layers "F.Cu" "F.Mask" "F.Paste")
			(net "GND")
		)
		(pad "165" smd rect
			(at 2.050034 -46.325028 90)
			(size 0.519938 1.4986)
			(layers "F.Cu" "F.Mask" "F.Paste")
			(net "M_J_CPU0_SA_DQ<11>")
		)
		(pad "166" smd rect
			(at 2.050034 -45.47489 90)
			(size 0.519938 1.4986)
			(layers "F.Cu" "F.Mask" "F.Paste")
			(net "GND")
		)
		(pad "167" smd rect
			(at 2.050034 -44.625006 90)
			(size 0.519938 1.4986)
			(layers "F.Cu" "F.Mask" "F.Paste")
			(net "M_J_CPU0_SA_DQS_DN<6>")
		)
		(pad "168" smd rect
			(at 2.050034 -43.775122 90)
			(size 0.519938 1.4986)
			(layers "F.Cu" "F.Mask" "F.Paste")
			(net "M_J_CPU0_SA_DQS_DP<6>")
		)
		(pad "169" smd rect
			(at 2.050034 -42.924984 90)
			(size 0.519938 1.4986)
			(layers "F.Cu" "F.Mask" "F.Paste")
			(net "GND")
		)
		(pad "170" smd rect
			(at 2.050034 -42.0751 90)
			(size 0.519938 1.4986)
			(layers "F.Cu" "F.Mask" "F.Paste")
			(net "M_J_CPU0_SA_DQ<14>")
		)
		(pad "171" smd rect
			(at 2.050034 -41.224962 90)
			(size 0.519938 1.4986)
			(layers "F.Cu" "F.Mask" "F.Paste")
			(net "GND")
		)
		(pad "172" smd rect
			(at 2.050034 -40.375078 90)
			(size 0.519938 1.4986)
			(layers "F.Cu" "F.Mask" "F.Paste")
			(net "M_J_CPU0_SA_DQ<15>")
		)
		(pad "173" smd rect
			(at 2.050034 -39.52494 90)
			(size 0.519938 1.4986)
			(layers "F.Cu" "F.Mask" "F.Paste")
			(net "GND")
		)
		(pad "174" smd rect
			(at 2.050034 -38.675056 90)
			(size 0.519938 1.4986)
			(layers "F.Cu" "F.Mask" "F.Paste")
			(net "M_J_CPU0_SA_DQ<18>")
		)
		(pad "175" smd rect
			(at 2.050034 -37.824918 90)
			(size 0.519938 1.4986)
			(layers "F.Cu" "F.Mask" "F.Paste")
			(net "GND")
		)
		(pad "176" smd rect
			(at 2.050034 -36.975034 90)
			(size 0.519938 1.4986)
			(layers "F.Cu" "F.Mask" "F.Paste")
			(net "M_J_CPU0_SA_DQ<19>")
		)
		(pad "177" smd rect
			(at 2.050034 -36.124896 90)
			(size 0.519938 1.4986)
			(layers "F.Cu" "F.Mask" "F.Paste")
			(net "GND")
		)
		(pad "178" smd rect
			(at 2.050034 -35.275012 90)
			(size 0.519938 1.4986)
			(layers "F.Cu" "F.Mask" "F.Paste")
			(net "M_J_CPU0_SA_DQS_DN<7>")
		)
		(pad "179" smd rect
			(at 2.050034 -34.425128 90)
			(size 0.519938 1.4986)
			(layers "F.Cu" "F.Mask" "F.Paste")
			(net "M_J_CPU0_SA_DQS_DP<7>")
		)
		(pad "180" smd rect
			(at 2.050034 -33.57499 90)
			(size 0.519938 1.4986)
			(layers "F.Cu" "F.Mask" "F.Paste")
			(net "GND")
		)
		(pad "181" smd rect
			(at 2.050034 -32.725106 90)
			(size 0.519938 1.4986)
			(layers "F.Cu" "F.Mask" "F.Paste")
			(net "M_J_CPU0_SA_DQ<22>")
		)
		(pad "182" smd rect
			(at 2.050034 -31.874968 90)
			(size 0.519938 1.4986)
			(layers "F.Cu" "F.Mask" "F.Paste")
			(net "GND")
		)
		(pad "183" smd rect
			(at 2.050034 -31.025084 90)
			(size 0.519938 1.4986)
			(layers "F.Cu" "F.Mask" "F.Paste")
			(net "M_J_CPU0_SA_DQ<23>")
		)
	)
)
